# BASEBOARD_FAB2 (Tioga Pass) — schematic netlist excerpt (pin names and nets, part order shuffled) for the footprints in the layout excerpt that follows; sources: Cadence DE-HDL packaged netlist, KiCad conversion of Wiwynn_Tioga_Pass_MB.brd

J4G3  SCONN288_H44441004  SCONN  pkg PIP  page 47
  \12v\(1)  = P12V_NVDIMM_ABC
  VSS(93)  = GND
  DQ(4)  = M_C_DQ<5>
  VSS(92)  = GND
  DQ(0)  = M_C_DQ<1>
  VSS(91)  = GND
  DQS9P  = M_C_DQS_DP<9>
  DQS9N  = M_C_DQS_DN<9>
  VSS(90)  = GND
  DQ(6)  = M_C_DQ<7>
  VSS(89)  = GND
  DQ(2)  = M_C_DQ<3>
  VSS(88)  = GND
  DQ(12)  = M_C_DQ<13>
  VSS(87)  = GND
  DQ(8)  = M_C_DQ<9>
  VSS(86)  = GND
  DQS10P  = M_C_DQS_DP<10>
  DQS10N  = M_C_DQS_DN<10>
  VSS(85)  = GND
  DQ(14)  = M_C_DQ<15>
  VSS(84)  = GND
  DQ(10)  = M_C_DQ<11>
  VSS(83)  = GND
  DQ(20)  = M_C_DQ<21>
  VSS(82)  = GND
  DQ(16)  = M_C_DQ<17>
  VSS(81)  = GND
  DQS11P  = M_C_DQS_DP<11>
  DQS11N  = M_C_DQS_DN<11>
  VSS(80)  = GND
  DQ(22)  = M_C_DQ<23>
  VSS(79)  = GND
  DQ(18)  = M_C_DQ<19>
  VSS(78)  = GND
  DQ(28)  = M_C_DQ<29>
  VSS(77)  = GND
  DQ(24)  = M_C_DQ<25>
  VSS(76)  = GND
  DQS12P  = M_C_DQS_DP<12>
  DQS12N  = M_C_DQS_DN<12>
  VSS(75)  = GND
  DQ(30)  = M_C_DQ<31>
  VSS(74)  = GND
  DQ(26)  = M_C_DQ<27>
  VSS(73)  = GND
  CB(4)  = M_C_ECC<5>
  VSS(72)  = GND
  CB(0)  = M_C_ECC<1>
  VSS(71)  = GND
  DQS17P  = M_C_DQS_DP<17>
  DQS17N  = M_C_DQS_DN<17>
  VSS(70)  = GND
  CB(6)  = M_C_ECC<7>
  VSS(69)  = GND
  CB(2)  = M_C_ECC<3>
  VSS(68)  = GND
  RESET_N  = M_ABC_RST_N
  VDD(25)  = PVDDQ_ABC
  CKE(0)  = M_C_CKE<0>
  VDD(24)  = PVDDQ_ABC
  ACT_N  = M_C_ACT_N
  BG(0)  = M_C_BG<0>
  VDD(23)  = PVDDQ_ABC
  A12  = M_C_MA<12>
  A9  = M_C_MA<9>
  VDD(22)  = PVDDQ_ABC
  A8  = M_C_MA<8>
  A6  = M_C_MA<6>
  VDD(21)  = PVDDQ_ABC
  A3  = M_C_MA<3>
  A1  = M_C_MA<1>
  VDD(20)  = PVDDQ_ABC
  CK0P  = M_C_CLK_DP<0>
  CK0N  = M_C_CLK_DN<0>
  VDD(19)  = PVDDQ_ABC
  VTT(1)  = PVTT_ABC
  EVENT_N  = FM_DIMM_EVENT_COD_N
  A0  = M_C_MA<0>
  VDD(18)  = PVDDQ_ABC
  BA(0)  = M_C_BA<0>
  A16_RAS_N  = M_C_MA<16>
  VDD(17)  = PVDDQ_ABC
  S0_N  = M_C_CS_N<0>
  VDD(16)  = PVDDQ_ABC
  A15_CAS_N  = M_C_MA<15>
  ODT(0)  = M_C_ODT<0>
  VDD(15)  = PVDDQ_ABC
  S1_N  = M_C_CS_N<1>
  VDD(14)  = PVDDQ_ABC
  ODT(1)  = M_C_ODT<1>
  VDD(13)  = PVDDQ_ABC
  S2_N_C(0)  = M_C_CS_N<2>
  VSS(67)  = GND
  DQ(36)  = M_C_DQ<37>
  VSS(66)  = GND
  DQ(32)  = M_C_DQ<33>
  VSS(65)  = GND
  DQS13P  = M_C_DQS_DP<13>
  DQS13N  = M_C_DQS_DN<13>
  VSS(64)  = GND
  DQ(38)  = M_C_DQ<39>
  VSS(63)  = GND
  DQ(34)  = M_C_DQ<35>
  VSS(62)  = GND
  DQ(44)  = M_C_DQ<45>
  VSS(61)  = GND
  DQ(40)  = M_C_DQ<41>
  VSS(60)  = GND
  DQS14P  = M_C_DQS_DP<14>
  DQS14N  = M_C_DQS_DN<14>
  VSS(59)  = GND
  DQ(46)  = M_C_DQ<47>
  VSS(58)  = GND
  DQ(42)  = M_C_DQ<43>
  VSS(57)  = GND
  DQ(52)  = M_C_DQ<53>
  VSS(56)  = GND
  DQ(48)  = M_C_DQ<49>
  VSS(55)  = GND
  DQS15P  = M_C_DQS_DP<15>
  DQS15N  = M_C_DQS_DN<15>
  VSS(54)  = GND
  DQ(54)  = M_C_DQ<55>
  VSS(53)  = GND
  DQ(50)  = M_C_DQ<51>
  VSS(52)  = GND
  DQ(60)  = M_C_DQ<61>
  VSS(51)  = GND
  DQ(56)  = M_C_DQ<57>
  VSS(50)  = GND
  DQS16P  = M_C_DQS_DP<16>
  DQS16N  = M_C_DQS_DN<16>
  VSS(49)  = GND
  DQ(62)  = M_C_DQ<63>
  VSS(48)  = GND
  DQ(58)  = M_C_DQ<59>
  VSS(47)  = GND
  SA(0)  = GND
  SA(1)  = GND
  SCL  = SMB_DDR_ABC_VPP_SCL
  VPP(4)  = PVPP_ABC
  VPP(3)  = PVPP_ABC
  RFU(2)  = TP_CH_C_DIMM_C0_RFU_2
  \12v\(0)  = P12V_NVDIMM_ABC
  VREFCA  = M_C_VREF
  VSS(46)  = GND
  DQ(5)  = M_C_DQ<4>
  VSS(45)  = GND
  DQ(1)  = M_C_DQ<0>
  VSS(44)  = GND
  DQS0N  = M_C_DQS_DN<0>
  DQS0P  = M_C_DQS_DP<0>
  VSS(43)  = GND
  DQ(7)  = M_C_DQ<6>
  VSS(42)  = GND
  DQ(3)  = M_C_DQ<2>
  VSS(41)  = GND
  DQ(13)  = M_C_DQ<12>
  VSS(40)  = GND
  DQ(9)  = M_C_DQ<8>
  VSS(39)  = GND
  DQS1N  = M_C_DQS_DN<1>
  DQS1P  = M_C_DQS_DP<1>
  VSS(38)  = GND
  DQ(15)  = M_C_DQ<14>
  VSS(37)  = GND
  DQ(11)  = M_C_DQ<10>
  VSS(36)  = GND
  DQ(21)  = M_C_DQ<20>
  VSS(35)  = GND
  DQ(17)  = M_C_DQ<16>
  VSS(34)  = GND
  DQS2N  = M_C_DQS_DN<2>
  DQS2P  = M_C_DQS_DP<2>
  VSS(33)  = GND
  DQ(23)  = M_C_DQ<22>
  VSS(32)  = GND
  DQ(19)  = M_C_DQ<18>
  VSS(31)  = GND
  DQ(29)  = M_C_DQ<28>
  VSS(30)  = GND
  DQ(25)  = M_C_DQ<24>
  VSS(29)  = GND
  DQS3N  = M_C_DQS_DN<3>
  DQS3P  = M_C_DQS_DP<3>
  VSS(28)  = GND
  DQ(31)  = M_C_DQ<30>
  VSS(27)  = GND
  DQ(27)  = M_C_DQ<26>
  VSS(26)  = GND
  CB(5)  = M_C_ECC<4>
  VSS(25)  = GND
  CB(1)  = M_C_ECC<0>
  VSS(24)  = GND
  DQS8N  = M_C_DQS_DN<8>
  DQS8P  = M_C_DQS_DP<8>
  VSS(23)  = GND
  CB(7)  = M_C_ECC<6>
  VSS(22)  = GND
  CB(3)  = M_C_ECC<2>
  VSS(21)  = GND
  CKE(1)  = M_C_CKE<1>
  VDD(12)  = PVDDQ_ABC
  RFU(0)  = TP_CH_C_DIMM_C0_RFU_0
  VDD(11)  = PVDDQ_ABC
  BG(1)  = M_C_BG<1>
  ALERT_N  = M_C_ALERT_N
  VDD(10)  = PVDDQ_ABC
  A11  = M_C_MA<11>
  A7  = M_C_MA<7>
  VDD(9)  = PVDDQ_ABC
  A5  = M_C_MA<5>
  A4  = M_C_MA<4>
  VDD(8)  = PVDDQ_ABC
  A2  = M_C_MA<2>
  VDD(7)  = PVDDQ_ABC
  CK1P  = M_C_CLK_DP<1>
  CK1N  = M_C_CLK_DN<1>
  VDD(6)  = PVDDQ_ABC
  VTT(0)  = PVTT_ABC
  PAR  = M_C_PAR
  VDD(5)  = PVDDQ_ABC
  BA(1)  = M_C_BA<1>
  A10  = M_C_MA<10>
  VDD(4)  = PVDDQ_ABC
  RFU(1)  = TP_CH_C_DIMM_C0_RFU_1
  A14_WE_N  = M_C_MA<14>
  VDD(3)  = PVDDQ_ABC
  SAVE_N_NC  = FM_ADR_COMPLETE_ABC_N
  VDD(2)  = PVDDQ_ABC
  A13  = M_C_MA<13>
  VDD(1)  = PVDDQ_ABC
  A17  = M_C_MA<17>
  C(2)  = M_C_C<2>
  VDD(0)  = PVDDQ_ABC
  S3_N_C(1)  = M_C_CS_N<3>
  SA(2)  = PVPP_ABC
  VSS(20)  = GND
  DQ(37)  = M_C_DQ<36>
  VSS(19)  = GND
  DQ(33)  = M_C_DQ<32>
  VSS(18)  = GND
  DQS4N  = M_C_DQS_DN<4>
  DQS4P  = M_C_DQS_DP<4>
  VSS(17)  = GND
  DQ(39)  = M_C_DQ<38>
  VSS(16)  = GND
  DQ(35)  = M_C_DQ<34>
  VSS(15)  = GND
  DQ(45)  = M_C_DQ<44>
  VSS(14)  = GND
  DQ(41)  = M_C_DQ<40>
  VSS(13)  = GND
  DQS5N  = M_C_DQS_DN<5>
  DQS5P  = M_C_DQS_DP<5>
  VSS(12)  = GND
  DQ(47)  = M_C_DQ<46>
  VSS(11)  = GND
  DQ(43)  = M_C_DQ<42>
  VSS(10)  = GND
  DQ(53)  = M_C_DQ<52>
  VSS(9)  = GND
  DQ(49)  = M_C_DQ<48>
  VSS(8)  = GND
  DQS6N  = M_C_DQS_DN<6>
  DQS6P  = M_C_DQS_DP<6>
  VSS(7)  = GND
  DQ(55)  = M_C_DQ<54>
  VSS(6)  = GND
  DQ(51)  = M_C_DQ<50>
  VSS(5)  = GND
  DQ(61)  = M_C_DQ<60>
  VSS(4)  = GND
  DQ(57)  = M_C_DQ<56>
  VSS(3)  = GND
  DQS7N  = M_C_DQS_DN<7>
  DQS7P  = M_C_DQS_DP<7>
  VSS(2)  = GND
  DQ(63)  = M_C_DQ<62>
  VSS(1)  = GND
  DQ(59)  = M_C_DQ<58>
  VSS(0)  = GND
  VDDSPD  = PVPP_ABC
  SDA  = SMB_DDR_ABC_VPP_SDA
  VPP(1)  = PVPP_ABC
  VPP(0)  = PVPP_ABC
  VPP(2)  = PVPP_ABC

(kicad_pcb
	(version 20260206)
	(generator "pcbnew")
	(generator_version "10.0")
	(general
		(thickness 1.6)
		(legacy_teardrops no)
	)
	(paper "A4")
	(title_block
		(title "Wiwynn_Tioga_Pass_MB.brd")
		(comment 1 "Tioga Pass / footprint 1441 of 4770 (J4G3), pads 252-291 of 291")
	)
	(layers
		(0 "F.Cu" signal "TOP")
		(4 "In1.Cu" signal "L2GND")
		(6 "In2.Cu" signal "L3")
		(8 "In3.Cu" signal "L4GND")
		(10 "In4.Cu" signal "L5")
		(12 "In5.Cu" signal "L6GND")
		(14 "In6.Cu" signal "L7VCC")
		(16 "In7.Cu" signal "L8VCC")
		(18 "In8.Cu" signal "L9GND")
		(20 "In9.Cu" signal "L10")
		(22 "In10.Cu" signal "L11GND")
		(24 "In11.Cu" signal "L12")
		(26 "In12.Cu" signal "L13GND")
		(2 "B.Cu" signal "BOTTOM")
		(9 "F.Adhes" user "F.Adhesive")
		(11 "B.Adhes" user "B.Adhesive")
		(13 "F.Paste" user "Package Geometry/Pastemask Top")
		(15 "B.Paste" user "Package Geometry/Pastemask Bottom")
		(5 "F.SilkS" user "Ref Des/Silkscreen Top")
		(7 "B.SilkS" user "Ref Des/Silkscreen Bottom")
		(1 "F.Mask" user "Board Geometry/Soldermask Top")
		(3 "B.Mask" user "Board Geometry/Soldermask Bottom")
		(17 "Dwgs.User" user "User.Drawings")
		(19 "Cmts.User" user "User.Comments")
		(21 "Eco1.User" user "User.Eco1")
		(23 "Eco2.User" user "User.Eco2")
		(25 "Edge.Cuts" user "Board Geometry/Outline")
		(27 "Margin" user)
		(31 "F.CrtYd" user "Package Geometry/Place Bound Top")
		(29 "B.CrtYd" user "Package Geometry/Place Bound Bottom")
		(35 "F.Fab" user "Ref Des/Assembly Top")
		(33 "B.Fab" user "Ref Des/Assembly Bottom")
	)
	(footprint ""
		(layer "F.Cu")
		(at 194.700398 3.778758 90)
		(property "Reference" "J4G3"
			(at 6.800088 37.20211 0)
			(unlocked yes)
			(layer "F.SilkS")
			(effects
				(font
					(size 0.7874 0.5842)
					(thickness 0.1524)
				)
				(justify left)
			)
		)
		(property "Value" ""
			(at 0 0 90)
			(layer "F.Fab")
			(effects
				(font
					(size 1.27 1.27)
				)
			)
		)
		(duplicate_pad_numbers_are_jumpers no)
		(pad "249" smd rect
			(at 4.59994 93.49994 90)
			(size 1.8034 0.508)
			(layers "F.Cu" "F.Mask" "F.Paste")
			(net "M_C_DQ<34>")
		)
		(pad "250" smd rect
			(at 4.59994 94.350078 90)
			(size 1.8034 0.508)
			(layers "F.Cu" "F.Mask" "F.Paste")
			(net "GND")
		)
		(pad "251" smd rect
			(at 4.59994 95.199962 90)
			(size 1.8034 0.508)
			(layers "F.Cu" "F.Mask" "F.Paste")
			(net "M_C_DQ<44>")
		)
		(pad "252" smd rect
			(at 4.59994 96.0501 90)
			(size 1.8034 0.508)
			(layers "F.Cu" "F.Mask" "F.Paste")
			(net "GND")
		)
		(pad "253" smd rect
			(at 4.59994 96.899984 90)
			(size 1.8034 0.508)
			(layers "F.Cu" "F.Mask" "F.Paste")
			(net "M_C_DQ<40>")
		)
		(pad "254" smd rect
			(at 4.59994 97.750122 90)
			(size 1.8034 0.508)
			(layers "F.Cu" "F.Mask" "F.Paste")
			(net "GND")
		)
		(pad "255" smd rect
			(at 4.59994 98.600006 90)
			(size 1.8034 0.508)
			(layers "F.Cu" "F.Mask" "F.Paste")
			(net "M_C_DQS_DN<5>")
		)
		(pad "256" smd rect
			(at 4.59994 99.44989 90)
			(size 1.8034 0.508)
			(layers "F.Cu" "F.Mask" "F.Paste")
			(net "M_C_DQS_DP<5>")
		)
		(pad "257" smd rect
			(at 4.59994 100.300028 90)
			(size 1.8034 0.508)
			(layers "F.Cu" "F.Mask" "F.Paste")
			(net "GND")
		)
		(pad "258" smd rect
			(at 4.59994 101.149912 90)
			(size 1.8034 0.508)
			(layers "F.Cu" "F.Mask" "F.Paste")
			(net "M_C_DQ<46>")
		)
		(pad "259" smd rect
			(at 4.59994 102.00005 90)
			(size 1.8034 0.508)
			(layers "F.Cu" "F.Mask" "F.Paste")
			(net "GND")
		)
		(pad "260" smd rect
			(at 4.59994 102.849934 90)
			(size 1.8034 0.508)
			(layers "F.Cu" "F.Mask" "F.Paste")
			(net "M_C_DQ<42>")
		)
		(pad "261" smd rect
			(at 4.59994 103.700072 90)
			(size 1.8034 0.508)
			(layers "F.Cu" "F.Mask" "F.Paste")
			(net "GND")
		)
		(pad "262" smd rect
			(at 4.59994 104.549956 90)
			(size 1.8034 0.508)
			(layers "F.Cu" "F.Mask" "F.Paste")
			(net "M_C_DQ<52>")
		)
		(pad "263" smd rect
			(at 4.59994 105.400094 90)
			(size 1.8034 0.508)
			(layers "F.Cu" "F.Mask" "F.Paste")
			(net "GND")
		)
		(pad "264" smd rect
			(at 4.59994 106.249978 90)
			(size 1.8034 0.508)
			(layers "F.Cu" "F.Mask" "F.Paste")
			(net "M_C_DQ<48>")
		)
		(pad "265" smd rect
			(at 4.59994 107.100116 90)
			(size 1.8034 0.508)
			(layers "F.Cu" "F.Mask" "F.Paste")
			(net "GND")
		)
		(pad "266" smd rect
			(at 4.59994 107.95 90)
			(size 1.8034 0.508)
			(layers "F.Cu" "F.Mask" "F.Paste")
			(net "M_C_DQS_DN<6>")
		)
		(pad "267" smd rect
			(at 4.59994 108.799884 90)
			(size 1.8034 0.508)
			(layers "F.Cu" "F.Mask" "F.Paste")
			(net "M_C_DQS_DP<6>")
		)
		(pad "268" smd rect
			(at 4.59994 109.650022 90)
			(size 1.8034 0.508)
			(layers "F.Cu" "F.Mask" "F.Paste")
			(net "GND")
		)
		(pad "269" smd rect
			(at 4.59994 110.499906 90)
			(size 1.8034 0.508)
			(layers "F.Cu" "F.Mask" "F.Paste")
			(net "M_C_DQ<54>")
		)
		(pad "270" smd rect
			(at 4.59994 111.350044 90)
			(size 1.8034 0.508)
			(layers "F.Cu" "F.Mask" "F.Paste")
			(net "GND")
		)
		(pad "271" smd rect
			(at 4.59994 112.199928 90)
			(size 1.8034 0.508)
			(layers "F.Cu" "F.Mask" "F.Paste")
			(net "M_C_DQ<50>")
		)
		(pad "272" smd rect
			(at 4.59994 113.050066 90)
			(size 1.8034 0.508)
			(layers "F.Cu" "F.Mask" "F.Paste")
			(net "GND")
		)
		(pad "273" smd rect
			(at 4.59994 113.89995 90)
			(size 1.8034 0.508)
			(layers "F.Cu" "F.Mask" "F.Paste")
			(net "M_C_DQ<60>")
		)
		(pad "274" smd rect
			(at 4.59994 114.750088 90)
			(size 1.8034 0.508)
			(layers "F.Cu" "F.Mask" "F.Paste")
			(net "GND")
		)
		(pad "275" smd rect
			(at 4.59994 115.599972 90)
			(size 1.8034 0.508)
			(layers "F.Cu" "F.Mask" "F.Paste")
			(net "M_C_DQ<56>")
		)
		(pad "276" smd rect
			(at 4.59994 116.45011 90)
			(size 1.8034 0.508)
			(layers "F.Cu" "F.Mask" "F.Paste")
			(net "GND")
		)
		(pad "277" smd rect
			(at 4.59994 117.299994 90)
			(size 1.8034 0.508)
			(layers "F.Cu" "F.Mask" "F.Paste")
			(net "M_C_DQS_DN<7>")
		)
		(pad "278" smd rect
			(at 4.59994 118.149878 90)
			(size 1.8034 0.508)
			(layers "F.Cu" "F.Mask" "F.Paste")
			(net "M_C_DQS_DP<7>")
		)
		(pad "279" smd rect
			(at 4.59994 119.000016 90)
			(size 1.8034 0.508)
			(layers "F.Cu" "F.Mask" "F.Paste")
			(net "GND")
		)
		(pad "280" smd rect
			(at 4.59994 119.8499 90)
			(size 1.8034 0.508)
			(layers "F.Cu" "F.Mask" "F.Paste")
			(net "M_C_DQ<62>")
		)
		(pad "281" smd rect
			(at 4.59994 120.700038 90)
			(size 1.8034 0.508)
			(layers "F.Cu" "F.Mask" "F.Paste")
			(net "GND")
		)
		(pad "282" smd rect
			(at 4.59994 121.549922 90)
			(size 1.8034 0.508)
			(layers "F.Cu" "F.Mask" "F.Paste")
			(net "M_C_DQ<58>")
		)
		(pad "283" smd rect
			(at 4.59994 122.40006 90)
			(size 1.8034 0.508)
			(layers "F.Cu" "F.Mask" "F.Paste")
			(net "GND")
		)
		(pad "284" smd rect
			(at 4.59994 123.249944 90)
			(size 1.8034 0.508)
			(layers "F.Cu" "F.Mask" "F.Paste")
			(net "PVPP_ABC")
		)
		(pad "285" smd rect
			(at 4.59994 124.100082 90)
			(size 1.8034 0.508)
			(layers "F.Cu" "F.Mask" "F.Paste")
			(net "SMB_DDR_ABC_VPP_SDA")
		)
		(pad "286" smd rect
			(at 4.59994 124.949966 90)
			(size 1.8034 0.508)
			(layers "F.Cu" "F.Mask" "F.Paste")
			(net "PVPP_ABC")
		)
		(pad "287" smd rect
			(at 4.59994 125.800104 90)
			(size 1.8034 0.508)
			(layers "F.Cu" "F.Mask" "F.Paste")
			(net "PVPP_ABC")
		)
		(pad "288" smd rect
			(at 4.59994 126.649988 90)
			(size 1.8034 0.508)
			(layers "F.Cu" "F.Mask" "F.Paste")
			(net "PVPP_ABC")
		)
	)
)
